# T6G (Grand Teton) — schematic netlist excerpt (pin names and nets, part order shuffled) for the footprints in the layout excerpt that follows; sources: Cadence DE-HDL packaged netlist, KiCad conversion of 04192023_DAF0TMB3IC0_F0TG_MB_C_brd_V02_OCP.brd

C147  Q_CAP  10UF 25V 10% X6S  pkg C0805  page 88 : A = P12V_MEM_CPU0 ; B = GND
C6107  Q_CAP  0.01UF 50V 10% X7R  pkg C0402  page 179 : A = P1V2_CPU0_USB2_DVDD12 ; B = GND
PC298_3  Q_CAP  22UF 16V 20% X6S  pkg C0805  page 212 : A = SW_P12V_AUX_PVDDCR_CPU0_P1_FLT ; B = GND

(kicad_pcb
	(version 20260206)
	(generator "pcbnew")
	(generator_version "10.0")
	(general
		(thickness 1.6)
		(legacy_teardrops no)
	)
	(paper "A4")
	(title_block
		(title "04192023_DAF0TMB3IC0_F0TG_MB_C_brd_V02_OCP.brd")
		(comment 1 "Grand Teton / footprints 6010-6012 of 8354")
	)
	(layers
		(0 "F.Cu" signal "TOP")
		(4 "In1.Cu" signal "GND")
		(6 "In2.Cu" signal "IN1")
		(8 "In3.Cu" signal "GND1")
		(10 "In4.Cu" signal "IN2")
		(12 "In5.Cu" signal "GND2")
		(14 "In6.Cu" signal "IN3")
		(16 "In7.Cu" signal "GND3")
		(18 "In8.Cu" signal "VCC")
		(20 "In9.Cu" signal "VCC1")
		(22 "In10.Cu" signal "GND4")
		(24 "In11.Cu" signal "IN4")
		(26 "In12.Cu" signal "GND5")
		(28 "In13.Cu" signal "IN5")
		(30 "In14.Cu" signal "GND6")
		(32 "In15.Cu" signal "IN6")
		(34 "In16.Cu" signal "GND7")
		(2 "B.Cu" signal "BOTTOM")
		(9 "F.Adhes" user "F.Adhesive")
		(11 "B.Adhes" user "B.Adhesive")
		(13 "F.Paste" user "Package Geometry/Pastemask Top")
		(15 "B.Paste" user "Package Geometry/Pastemask Bottom")
		(5 "F.SilkS" user "Ref Des/Silkscreen Top")
		(7 "B.SilkS" user "Ref Des/Silkscreen Bottom")
		(1 "F.Mask" user "Board Geometry/Soldermask Top")
		(3 "B.Mask" user "Board Geometry/Soldermask Bottom")
		(17 "Dwgs.User" user "User.Drawings")
		(19 "Cmts.User" user "User.Comments")
		(21 "Eco1.User" user "User.Eco1")
		(23 "Eco2.User" user "User.Eco2")
		(25 "Edge.Cuts" user "Board Geometry/Outline")
		(27 "Margin" user)
		(31 "F.CrtYd" user "Package Geometry/Place Bound Top")
		(29 "B.CrtYd" user "Package Geometry/Place Bound Bottom")
		(35 "F.Fab" user "Ref Des/Assembly Top")
		(33 "B.Fab" user "Ref Des/Assembly Bottom")
	)
	(footprint ""
		(layer "B.Cu")
		(at 114.01806 -28.449778 -90)
		(property "Reference" "C6107"
			(at 0 0 90)
			(layer "B.SilkS")
			(hide yes)
			(effects
				(font
					(size 1.27 1.27)
				)
				(justify mirror)
			)
		)
		(property "Value" ""
			(at 0 0 90)
			(layer "B.Fab")
			(effects
				(font
					(size 1.27 1.27)
				)
				(justify mirror)
			)
		)
		(duplicate_pad_numbers_are_jumpers no)
		(fp_line
			(start -0.7874 0.4064)
			(end 0.7874 0.4064)
			(stroke
				(width 0.1524)
				(type default)
			)
			(layer "B.SilkS")
		)
		(fp_line
			(start 0.7874 0.4064)
			(end 0.7874 -0.4064)
			(stroke
				(width 0.1524)
				(type default)
			)
			(layer "B.SilkS")
		)
		(fp_line
			(start -0.7874 -0.4064)
			(end -0.7874 0.4064)
			(stroke
				(width 0.1524)
				(type default)
			)
			(layer "B.SilkS")
		)
		(fp_line
			(start 0.7874 -0.4064)
			(end -0.7874 -0.4064)
			(stroke
				(width 0.1524)
				(type default)
			)
			(layer "B.SilkS")
		)
		(fp_line
			(start -0.67945 0.3048)
			(end -0.120396 0.3048)
			(stroke
				(width 0.1)
				(type default)
			)
			(layer "B.Fab")
		)
		(fp_line
			(start -0.120396 0.3048)
			(end -0.120396 0.2794)
			(stroke
				(width 0.1)
				(type default)
			)
			(layer "B.Fab")
		)
		(fp_line
			(start 0.12065 0.3048)
			(end 0.67945 0.3048)
			(stroke
				(width 0.1)
				(type default)
			)
			(layer "B.Fab")
		)
		(fp_line
			(start 0.67945 0.3048)
			(end 0.67945 -0.305054)
			(stroke
				(width 0.1)
				(type default)
			)
			(layer "B.Fab")
		)
		(fp_line
			(start -0.120396 0.2794)
			(end 0.12065 0.2794)
			(stroke
				(width 0.1)
				(type default)
			)
			(layer "B.Fab")
		)
		(fp_line
			(start 0.12065 0.2794)
			(end 0.12065 0.3048)
			(stroke
				(width 0.1)
				(type default)
			)
			(layer "B.Fab")
		)
		(fp_line
			(start -0.12065 -0.2794)
			(end -0.12065 -0.3048)
			(stroke
				(width 0.1)
				(type default)
			)
			(layer "B.Fab")
		)
		(fp_line
			(start 0.12065 -0.2794)
			(end -0.12065 -0.2794)
			(stroke
				(width 0.1)
				(type default)
			)
			(layer "B.Fab")
		)
		(fp_line
			(start -0.67945 -0.3048)
			(end -0.67945 0.3048)
			(stroke
				(width 0.1)
				(type default)
			)
			(layer "B.Fab")
		)
		(fp_line
			(start -0.12065 -0.3048)
			(end -0.67945 -0.3048)
			(stroke
				(width 0.1)
				(type default)
			)
			(layer "B.Fab")
		)
		(fp_line
			(start 0.12065 -0.305054)
			(end 0.12065 -0.2794)
			(stroke
				(width 0.1)
				(type default)
			)
			(layer "B.Fab")
		)
		(fp_line
			(start 0.67945 -0.305054)
			(end 0.12065 -0.305054)
			(stroke
				(width 0.1)
				(type default)
			)
			(layer "B.Fab")
		)
		(pad "1" smd circle
			(at 0.40005 0 90)
			(size 0 0)
			(layers "B.Cu" "B.Mask" "B.Paste")
			(net "P1V2_CPU0_USB2_DVDD12")
		)
		(pad "2" smd circle
			(at -0.40005 0 90)
			(size 0 0)
			(layers "B.Cu" "B.Mask" "B.Paste")
			(net "GND")
		)
	)
	(footprint ""
		(layer "B.Cu")
		(at 95.964248 -182.555134 -90)
		(property "Reference" "PC298_3"
			(at 0 0 90)
			(layer "B.SilkS")
			(hide yes)
			(effects
				(font
					(size 1.27 1.27)
				)
				(justify mirror)
			)
		)
		(property "Value" ""
			(at 0 0 90)
			(layer "B.Fab")
			(effects
				(font
					(size 1.27 1.27)
				)
				(justify mirror)
			)
		)
		(duplicate_pad_numbers_are_jumpers no)
		(fp_line
			(start -1.524 0.762)
			(end 1.524 0.762)
			(stroke
				(width 0.1524)
				(type default)
			)
			(layer "B.SilkS")
		)
		(fp_line
			(start 1.524 0.762)
			(end 1.524 -0.762)
			(stroke
				(width 0.1524)
				(type default)
			)
			(layer "B.SilkS")
		)
		(fp_line
			(start -1.524 -0.762)
			(end -1.524 0.762)
			(stroke
				(width 0.1524)
				(type default)
			)
			(layer "B.SilkS")
		)
		(fp_line
			(start 1.524 -0.762)
			(end -1.524 -0.762)
			(stroke
				(width 0.1524)
				(type default)
			)
			(layer "B.SilkS")
		)
		(fp_line
			(start -1.1049 0.724916)
			(end -1.1049 -0.724916)
			(stroke
				(width 0.1)
				(type default)
			)
			(layer "B.Fab")
		)
		(fp_line
			(start 1.1049 0.724916)
			(end -1.1049 0.724916)
			(stroke
				(width 0.1)
				(type default)
			)
			(layer "B.Fab")
		)
		(fp_line
			(start -1.1049 -0.724916)
			(end 1.1049 -0.724916)
			(stroke
				(width 0.1)
				(type default)
			)
			(layer "B.Fab")
		)
		(fp_line
			(start 1.1049 -0.724916)
			(end 1.1049 0.724916)
			(stroke
				(width 0.1)
				(type default)
			)
			(layer "B.Fab")
		)
		(pad "1" smd rect
			(at 0.889 0 270)
			(size 1.016 1.27)
			(layers "B.Cu" "B.Mask" "B.Paste")
			(net "SW_P12V_AUX_PVDDCR_CPU0_P1_FLT")
		)
		(pad "2" smd rect
			(at -0.889 0 270)
			(size 1.016 1.27)
			(layers "B.Cu" "B.Mask" "B.Paste")
			(net "GND")
		)
	)
	(footprint ""
		(layer "B.Cu")
		(at 292.28034 -192.660016)
		(property "Reference" "C147"
			(at 0 0 0)
			(layer "B.SilkS")
			(hide yes)
			(effects
				(font
					(size 1.27 1.27)
				)
				(justify mirror)
			)
		)
		(property "Value" ""
			(at 0 0 0)
			(layer "B.Fab")
			(effects
				(font
					(size 1.27 1.27)
				)
				(justify mirror)
			)
		)
		(duplicate_pad_numbers_are_jumpers no)
		(fp_line
			(start -1.524 -0.762)
			(end -1.524 0.762)
			(stroke
				(width 0.1524)
				(type default)
			)
			(layer "B.SilkS")
		)
		(fp_line
			(start -1.524 0.762)
			(end 1.524 0.762)
			(stroke
				(width 0.1524)
				(type default)
			)
			(layer "B.SilkS")
		)
		(fp_line
			(start 1.524 -0.762)
			(end -1.524 -0.762)
			(stroke
				(width 0.1524)
				(type default)
			)
			(layer "B.SilkS")
		)
		(fp_line
			(start 1.524 0.762)
			(end 1.524 -0.762)
			(stroke
				(width 0.1524)
				(type default)
			)
			(layer "B.SilkS")
		)
		(fp_line
			(start -1.1049 -0.724916)
			(end 1.1049 -0.724916)
			(stroke
				(width 0.1)
				(type default)
			)
			(layer "B.Fab")
		)
		(fp_line
			(start -1.1049 0.724916)
			(end -1.1049 -0.724916)
			(stroke
				(width 0.1)
				(type default)
			)
			(layer "B.Fab")
		)
		(fp_line
			(start 1.1049 -0.724916)
			(end 1.1049 0.724916)
			(stroke
				(width 0.1)
				(type default)
			)
			(layer "B.Fab")
		)
		(fp_line
			(start 1.1049 0.724916)
			(end -1.1049 0.724916)
			(stroke
				(width 0.1)
				(type default)
			)
			(layer "B.Fab")
		)
		(pad "1" smd rect
			(at 0.889 0)
			(size 1.016 1.27)
			(layers "B.Cu" "B.Mask" "B.Paste")
			(net "P12V_MEM_CPU0")
		)
		(pad "2" smd rect
			(at -0.889 0)
			(size 1.016 1.27)
			(layers "B.Cu" "B.Mask" "B.Paste")
			(net "GND")
		)
	)
)
